(kicad_pcb
	(version 20260206)
	(generator "pcbnew")
	(generator_version "10.0")
	(general
		(thickness 1.6)
		(legacy_teardrops no)
	)
	(paper "A4")
	(title_block
		(title "Bryce Canyon_F.DPB_16315-1-OCP.brd")
		(comment 1 "Bryce Canyon / footprints 73-79 of 2223")
	)
	(layers
		(0 "F.Cu" signal "TOP")
		(4 "In1.Cu" signal "L2GND")
		(6 "In2.Cu" signal "L3")
		(8 "In3.Cu" signal "L4GND")
		(10 "In4.Cu" signal "L5")
		(12 "In5.Cu" signal "L6VCC")
		(14 "In6.Cu" signal "L7VCC")
		(16 "In7.Cu" signal "L8")
		(18 "In8.Cu" signal "L9GND")
		(20 "In9.Cu" signal "L10")
		(22 "In10.Cu" signal "L11GND")
		(2 "B.Cu" signal "BOTTOM")
		(9 "F.Adhes" user "F.Adhesive")
		(11 "B.Adhes" user "B.Adhesive")
		(13 "F.Paste" user "Package Geometry/Pastemask Top")
		(15 "B.Paste" user "Package Geometry/Pastemask Bottom")
		(5 "F.SilkS" user "Ref Des/Silkscreen Top")
		(7 "B.SilkS" user "Ref Des/Silkscreen Bottom")
		(1 "F.Mask" user "Board Geometry/Soldermask Top")
		(3 "B.Mask" user "Board Geometry/Soldermask Bottom")
		(17 "Dwgs.User" user "User.Drawings")
		(19 "Cmts.User" user "User.Comments")
		(21 "Eco1.User" user "User.Eco1")
		(23 "Eco2.User" user "User.Eco2")
		(25 "Edge.Cuts" user "Board Geometry/Outline")
		(27 "Margin" user)
		(31 "F.CrtYd" user "Package Geometry/Place Bound Top")
		(29 "B.CrtYd" user "Package Geometry/Place Bound Bottom")
		(35 "F.Fab" user "Ref Des/Assembly Top")
		(33 "B.Fab" user "Ref Des/Assembly Bottom")
	)
	(footprint ""
		(layer "F.Cu")
		(at 340.007194 -242.799362 180)
		(property "Reference" "Q270"
			(at 0 0 180)
			(layer "F.SilkS")
			(hide yes)
			(effects
				(font
					(size 1.27 1.27)
				)
			)
		)
		(property "Value" "SSM3K324R-GP"
			(at 0.127 -8.9662 180)
			(unlocked yes)
			(layer "F.Fab")
			(hide yes)
			(effects
				(font
					(size 1.016 1.016)
					(thickness 0.1524)
				)
			)
		)
		(property "Device Type" "SOT23DGS2D4H35"
			(at 0.127 -10.4902 180)
			(unlocked yes)
			(layer "F.Fab")
			(hide yes)
			(effects
				(font
					(size 1.016 1.016)
					(thickness 0.1524)
				)
			)
		)
		(duplicate_pad_numbers_are_jumpers no)
		(fp_line
			(start 1.651 1.778)
			(end 1.651 -1.778)
			(stroke
				(width 0.1524)
				(type default)
			)
			(layer "F.SilkS")
		)
		(fp_line
			(start 1.651 -1.778)
			(end -1.651 -1.778)
			(stroke
				(width 0.1524)
				(type default)
			)
			(layer "F.SilkS")
		)
		(fp_line
			(start -1.651 1.778)
			(end 1.651 1.778)
			(stroke
				(width 0.1524)
				(type default)
			)
			(layer "F.SilkS")
		)
		(fp_line
			(start -1.651 -1.778)
			(end -1.651 1.778)
			(stroke
				(width 0.1524)
				(type default)
			)
			(layer "F.SilkS")
		)
		(fp_poly
			(pts
				(xy -1.778 1.8796) (xy -1.778 -1.8796) (xy 1.778 -1.8796) (xy 1.778 1.8796)
			)
			(stroke
				(width 0)
				(type default)
			)
			(fill no)
			(layer "F.CrtYd")
		)
		(fp_poly
			(pts
				(xy -1.778 1.8796) (xy -1.778 -1.8796) (xy 1.778 -1.8796) (xy 1.778 1.8796)
			)
			(stroke
				(width 0)
				(type default)
			)
			(fill no)
			(layer "F.Fab")
		)
		(pad "D" smd custom
			(at 0 -0.9525 180)
			(size 0.1905 0.1905)
			(layers "F.Cu" "F.Mask" "F.Paste")
			(net "DRV_ACT_7_N")
			(options
				(clearance outline)
				(anchor circle)
			)
			(primitives
				(gr_poly
					(pts
						(arc
							(start -0.1778 0.5715)
							(mid -0.321484 0.511984)
							(end -0.381 0.3683)
						)
						(arc
							(start -0.381 -0.3683)
							(mid -0.321484 -0.511984)
							(end -0.1778 -0.5715)
						)
						(arc
							(start 0.1778 -0.5715)
							(mid 0.321484 -0.511984)
							(end 0.381 -0.3683)
						)
						(arc
							(start 0.381 0.3683)
							(mid 0.321484 0.511984)
							(end 0.1778 0.5715)
						)
					)
					(width 0)
					(fill yes)
				)
			)
		)
		(pad "G" smd custom
			(at -0.98425 0.9525 180)
			(size 0.1905 0.1905)
			(layers "F.Cu" "F.Mask" "F.Paste")
			(net "DRIVE_A_7_ACT")
			(options
				(clearance outline)
				(anchor circle)
			)
			(primitives
				(gr_poly
					(pts
						(arc
							(start -0.1778 0.5715)
							(mid -0.321484 0.511984)
							(end -0.381 0.3683)
						)
						(arc
							(start -0.381 -0.3683)
							(mid -0.321484 -0.511984)
							(end -0.1778 -0.5715)
						)
						(arc
							(start 0.1778 -0.5715)
							(mid 0.321484 -0.511984)
							(end 0.381 -0.3683)
						)
						(arc
							(start 0.381 0.3683)
							(mid 0.321484 0.511984)
							(end 0.1778 0.5715)
						)
					)
					(width 0)
					(fill yes)
				)
			)
		)
		(pad "S" smd custom
			(at 0.98425 0.9525 180)
			(size 0.1905 0.1905)
			(layers "F.Cu" "F.Mask" "F.Paste")
			(net "GND")
			(options
				(clearance outline)
				(anchor circle)
			)
			(primitives
				(gr_poly
					(pts
						(arc
							(start -0.1778 0.5715)
							(mid -0.321484 0.511984)
							(end -0.381 0.3683)
						)
						(arc
							(start -0.381 -0.3683)
							(mid -0.321484 -0.511984)
							(end -0.1778 -0.5715)
						)
						(arc
							(start 0.1778 -0.5715)
							(mid 0.321484 -0.511984)
							(end 0.381 -0.3683)
						)
						(arc
							(start 0.381 0.3683)
							(mid 0.321484 0.511984)
							(end 0.1778 0.5715)
						)
					)
					(width 0)
					(fill yes)
				)
			)
		)
	)
	(footprint ""
		(layer "F.Cu")
		(at 447.455036 -245.302024 -90)
		(property "Reference" "R495"
			(at 0 0 270)
			(layer "F.SilkS")
			(hide yes)
			(effects
				(font
					(size 1.27 1.27)
				)
			)
		)
		(property "Value" "4K7R2J-2-GP"
			(at 0.064008 -3.993896 270)
			(unlocked yes)
			(layer "F.Fab")
			(hide yes)
			(effects
				(font
					(size 1.016 1.016)
					(thickness 0.1524)
				)
			)
		)
		(property "Device Type" "R402H16"
			(at 0.064008 -5.517896 270)
			(unlocked yes)
			(layer "F.Fab")
			(hide yes)
			(effects
				(font
					(size 1.016 1.016)
					(thickness 0.1524)
				)
			)
		)
		(duplicate_pad_numbers_are_jumpers no)
		(fp_line
			(start -0.508 -0.9398)
			(end -0.508 0.9398)
			(stroke
				(width 0.1524)
				(type default)
			)
			(layer "F.SilkS")
		)
		(fp_line
			(start 0.508 -0.9398)
			(end -0.508 -0.9398)
			(stroke
				(width 0.1524)
				(type default)
			)
			(layer "F.SilkS")
		)
		(fp_rect
			(start -0.508 0.9398)
			(end 0.508 -0.9398)
			(stroke
				(width 0)
				(type default)
			)
			(fill no)
			(layer "F.CrtYd")
		)
		(fp_rect
			(start -0.508 0.9398)
			(end 0.508 -0.9398)
			(stroke
				(width 0)
				(type default)
			)
			(fill no)
			(layer "F.Fab")
		)
		(pad "1" smd custom
			(at 0 -0.4445 270)
			(size 0.1397 0.1397)
			(layers "F.Cu" "F.Mask" "F.Paste")
			(net "DRIVE_A_10_FLT_LED")
			(options
				(clearance outline)
				(anchor circle)
			)
			(primitives
				(gr_poly
					(pts
						(arc
							(start -0.1778 -0.2794)
							(mid -0.249642 -0.249642)
							(end -0.2794 -0.1778)
						)
						(arc
							(start -0.2794 0.1778)
							(mid -0.249642 0.249642)
							(end -0.1778 0.2794)
						)
						(arc
							(start 0.1778 0.2794)
							(mid 0.249642 0.249642)
							(end 0.2794 0.1778)
						)
						(arc
							(start 0.2794 -0.1778)
							(mid 0.249642 -0.249642)
							(end 0.1778 -0.2794)
						)
					)
					(width 0)
					(fill yes)
				)
			)
		)
		(pad "2" smd custom
			(at 0 0.4445 270)
			(size 0.1397 0.1397)
			(layers "F.Cu" "F.Mask" "F.Paste")
			(net "GND")
			(options
				(clearance outline)
				(anchor circle)
			)
			(primitives
				(gr_poly
					(pts
						(arc
							(start -0.1778 -0.2794)
							(mid -0.249642 -0.249642)
							(end -0.2794 -0.1778)
						)
						(arc
							(start -0.2794 0.1778)
							(mid -0.249642 0.249642)
							(end -0.1778 0.2794)
						)
						(arc
							(start 0.1778 0.2794)
							(mid 0.249642 0.249642)
							(end 0.2794 0.1778)
						)
						(arc
							(start 0.2794 -0.1778)
							(mid 0.249642 -0.249642)
							(end 0.1778 -0.2794)
						)
					)
					(width 0)
					(fill yes)
				)
			)
		)
	)
	(footprint ""
		(layer "F.Cu")
		(at 378.864876 -242.25377)
		(property "Reference" "R250"
			(at 0 0 0)
			(layer "F.SilkS")
			(hide yes)
			(effects
				(font
					(size 1.27 1.27)
				)
			)
		)
		(property "Value" "91R3F-1-GP"
			(at -0.0254 -2.5146 0)
			(unlocked yes)
			(layer "F.Fab")
			(hide yes)
			(effects
				(font
					(size 1.016 1.016)
					(thickness 0.1524)
				)
			)
		)
		(property "Device Type" "R603H22"
			(at -0.0254 -4.0386 0)
			(unlocked yes)
			(layer "F.Fab")
			(hide yes)
			(effects
				(font
					(size 1.016 1.016)
					(thickness 0.1524)
				)
			)
		)
		(duplicate_pad_numbers_are_jumpers no)
		(fp_line
			(start -0.4826 0)
			(end -0.2032 0)
			(stroke
				(width 0.2032)
				(type default)
			)
			(layer "F.SilkS")
		)
		(fp_line
			(start 0.2032 0)
			(end 0.4826 0)
			(stroke
				(width 0.2032)
				(type default)
			)
			(layer "F.SilkS")
		)
		(fp_rect
			(start -0.5842 1.3335)
			(end 0.5842 -1.3335)
			(stroke
				(width 0)
				(type default)
			)
			(fill no)
			(layer "F.CrtYd")
		)
		(fp_rect
			(start -0.5842 1.3335)
			(end 0.5842 -1.3335)
			(stroke
				(width 0)
				(type default)
			)
			(fill no)
			(layer "F.Fab")
		)
		(pad "1" smd custom
			(at 0 -0.762)
			(size 0.2159 0.2159)
			(layers "F.Cu" "F.Mask" "F.Paste")
			(net "P5V_A_3")
			(options
				(clearance outline)
				(anchor circle)
			)
			(primitives
				(gr_poly
					(pts
						(arc
							(start -0.3302 -0.4318)
							(mid -0.402042 -0.402042)
							(end -0.4318 -0.3302)
						)
						(arc
							(start -0.4318 0.3302)
							(mid -0.402042 0.402042)
							(end -0.3302 0.4318)
						)
						(arc
							(start 0.3302 0.4318)
							(mid 0.402042 0.402042)
							(end 0.4318 0.3302)
						)
						(arc
							(start 0.4318 -0.3302)
							(mid 0.402042 -0.402042)
							(end 0.3302 -0.4318)
						)
					)
					(width 0)
					(fill yes)
				)
			)
		)
		(pad "2" smd custom
			(at 0 0.762)
			(size 0.2159 0.2159)
			(layers "F.Cu" "F.Mask" "F.Paste")
			(net "DRV_ACT_8")
			(options
				(clearance outline)
				(anchor circle)
			)
			(primitives
				(gr_poly
					(pts
						(arc
							(start -0.3302 -0.4318)
							(mid -0.402042 -0.402042)
							(end -0.4318 -0.3302)
						)
						(arc
							(start -0.4318 0.3302)
							(mid -0.402042 0.402042)
							(end -0.3302 0.4318)
						)
						(arc
							(start 0.3302 0.4318)
							(mid 0.402042 0.402042)
							(end 0.4318 0.3302)
						)
						(arc
							(start 0.4318 -0.3302)
							(mid 0.402042 -0.402042)
							(end 0.3302 -0.4318)
						)
					)
					(width 0)
					(fill yes)
				)
			)
		)
	)
	(footprint ""
		(layer "F.Cu")
		(at 154.29484 -143.198596 180)
		(property "Reference" "C552"
			(at 0 0 180)
			(layer "F.SilkS")
			(hide yes)
			(effects
				(font
					(size 1.27 1.27)
				)
			)
		)
		(property "Value" "SC1U16V3KX-5GP"
			(at 0 -2.8194 180)
			(unlocked yes)
			(layer "F.Fab")
			(hide yes)
			(effects
				(font
					(size 1.016 1.016)
					(thickness 0.1524)
				)
			)
		)
		(property "Device Type" "C603H36"
			(at 0 -4.3434 180)
			(unlocked yes)
			(layer "F.Fab")
			(hide yes)
			(effects
				(font
					(size 1.016 1.016)
					(thickness 0.1524)
				)
			)
		)
		(duplicate_pad_numbers_are_jumpers no)
		(fp_line
			(start 0.508 0)
			(end -0.508 0)
			(stroke
				(width 0.2032)
				(type default)
			)
			(layer "F.SilkS")
		)
		(fp_rect
			(start -0.5842 1.3335)
			(end 0.5842 -1.3335)
			(stroke
				(width 0)
				(type default)
			)
			(fill no)
			(layer "F.CrtYd")
		)
		(fp_rect
			(start -0.5842 1.3335)
			(end 0.5842 -1.3335)
			(stroke
				(width 0)
				(type default)
			)
			(fill no)
			(layer "F.Fab")
		)
		(pad "1" smd custom
			(at 0 -0.762 180)
			(size 0.2159 0.2159)
			(layers "F.Cu" "F.Mask" "F.Paste")
			(net "MB0_CM_OV_R")
			(options
				(clearance outline)
				(anchor circle)
			)
			(primitives
				(gr_poly
					(pts
						(arc
							(start -0.3302 -0.4318)
							(mid -0.402042 -0.402042)
							(end -0.4318 -0.3302)
						)
						(arc
							(start -0.4318 0.3302)
							(mid -0.402042 0.402042)
							(end -0.3302 0.4318)
						)
						(arc
							(start 0.3302 0.4318)
							(mid 0.402042 0.402042)
							(end 0.4318 0.3302)
						)
						(arc
							(start 0.4318 -0.3302)
							(mid 0.402042 -0.402042)
							(end 0.3302 -0.4318)
						)
					)
					(width 0)
					(fill yes)
				)
			)
		)
		(pad "2" smd custom
			(at 0 0.762 180)
			(size 0.2159 0.2159)
			(layers "F.Cu" "F.Mask" "F.Paste")
			(net "AGND_CURRENT_MONOA")
			(options
				(clearance outline)
				(anchor circle)
			)
			(primitives
				(gr_poly
					(pts
						(arc
							(start -0.3302 -0.4318)
							(mid -0.402042 -0.402042)
							(end -0.4318 -0.3302)
						)
						(arc
							(start -0.4318 0.3302)
							(mid -0.402042 0.402042)
							(end -0.3302 0.4318)
						)
						(arc
							(start 0.3302 0.4318)
							(mid 0.402042 0.402042)
							(end 0.4318 0.3302)
						)
						(arc
							(start 0.4318 -0.3302)
							(mid 0.402042 -0.402042)
							(end 0.3302 -0.4318)
						)
					)
					(width 0)
					(fill yes)
				)
			)
		)
	)
	(footprint ""
		(layer "F.Cu")
		(at 49.469802 -148.64715 -90)
		(property "Reference" "C620"
			(at 0 0 270)
			(layer "F.SilkS")
			(hide yes)
			(effects
				(font
					(size 1.27 1.27)
				)
			)
		)
		(property "Value" "SC1U16V3KX-5GP"
			(at 0 -2.8194 270)
			(unlocked yes)
			(layer "F.Fab")
			(hide yes)
			(effects
				(font
					(size 1.016 1.016)
					(thickness 0.1524)
				)
			)
		)
		(property "Device Type" "C603H36"
			(at 0 -4.3434 270)
			(unlocked yes)
			(layer "F.Fab")
			(hide yes)
			(effects
				(font
					(size 1.016 1.016)
					(thickness 0.1524)
				)
			)
		)
		(duplicate_pad_numbers_are_jumpers no)
		(fp_line
			(start 0.508 0)
			(end -0.508 0)
			(stroke
				(width 0.2032)
				(type default)
			)
			(layer "F.SilkS")
		)
		(fp_rect
			(start -0.5842 1.3335)
			(end 0.5842 -1.3335)
			(stroke
				(width 0)
				(type default)
			)
			(fill no)
			(layer "F.CrtYd")
		)
		(fp_rect
			(start -0.5842 1.3335)
			(end 0.5842 -1.3335)
			(stroke
				(width 0)
				(type default)
			)
			(fill no)
			(layer "F.Fab")
		)
		(pad "1" smd custom
			(at 0 -0.762 270)
			(size 0.2159 0.2159)
			(layers "F.Cu" "F.Mask" "F.Paste")
			(net "P5V_B_EN_R")
			(options
				(clearance outline)
				(anchor circle)
			)
			(primitives
				(gr_poly
					(pts
						(arc
							(start -0.3302 -0.4318)
							(mid -0.402042 -0.402042)
							(end -0.4318 -0.3302)
						)
						(arc
							(start -0.4318 0.3302)
							(mid -0.402042 0.402042)
							(end -0.3302 0.4318)
						)
						(arc
							(start 0.3302 0.4318)
							(mid 0.402042 0.402042)
							(end 0.4318 0.3302)
						)
						(arc
							(start 0.4318 -0.3302)
							(mid 0.402042 -0.402042)
							(end 0.3302 -0.4318)
						)
					)
					(width 0)
					(fill yes)
				)
			)
		)
		(pad "2" smd custom
			(at 0 0.762 270)
			(size 0.2159 0.2159)
			(layers "F.Cu" "F.Mask" "F.Paste")
			(net "GND")
			(options
				(clearance outline)
				(anchor circle)
			)
			(primitives
				(gr_poly
					(pts
						(arc
							(start -0.3302 -0.4318)
							(mid -0.402042 -0.402042)
							(end -0.4318 -0.3302)
						)
						(arc
							(start -0.4318 0.3302)
							(mid -0.402042 0.402042)
							(end -0.3302 0.4318)
						)
						(arc
							(start 0.3302 0.4318)
							(mid 0.402042 0.402042)
							(end 0.4318 0.3302)
						)
						(arc
							(start 0.4318 -0.3302)
							(mid 0.402042 -0.402042)
							(end 0.3302 -0.4318)
						)
					)
					(width 0)
					(fill yes)
				)
			)
		)
	)
	(footprint ""
		(layer "F.Cu")
		(at 406.14473 -130.408172 -90)
		(property "Reference" "R541"
			(at 0 0 270)
			(layer "F.SilkS")
			(hide yes)
			(effects
				(font
					(size 1.27 1.27)
				)
			)
		)
		(property "Value" "4K7R2J-2-GP"
			(at 0.064008 -3.993896 270)
			(unlocked yes)
			(layer "F.Fab")
			(hide yes)
			(effects
				(font
					(size 1.016 1.016)
					(thickness 0.1524)
				)
			)
		)
		(property "Device Type" "R402H16"
			(at 0.064008 -5.517896 270)
			(unlocked yes)
			(layer "F.Fab")
			(hide yes)
			(effects
				(font
					(size 1.016 1.016)
					(thickness 0.1524)
				)
			)
		)
		(duplicate_pad_numbers_are_jumpers no)
		(fp_line
			(start -0.508 -0.9398)
			(end -0.508 0.9398)
			(stroke
				(width 0.1524)
				(type default)
			)
			(layer "F.SilkS")
		)
		(fp_line
			(start 0.508 -0.9398)
			(end -0.508 -0.9398)
			(stroke
				(width 0.1524)
				(type default)
			)
			(layer "F.SilkS")
		)
		(fp_rect
			(start -0.508 0.9398)
			(end 0.508 -0.9398)
			(stroke
				(width 0)
				(type default)
			)
			(fill no)
			(layer "F.CrtYd")
		)
		(fp_rect
			(start -0.508 0.9398)
			(end 0.508 -0.9398)
			(stroke
				(width 0)
				(type default)
			)
			(fill no)
			(layer "F.Fab")
		)
		(pad "1" smd custom
			(at 0 -0.4445 270)
			(size 0.1397 0.1397)
			(layers "F.Cu" "F.Mask" "F.Paste")
			(net "DRIVE_A_21_FLT_LED")
			(options
				(clearance outline)
				(anchor circle)
			)
			(primitives
				(gr_poly
					(pts
						(arc
							(start -0.1778 -0.2794)
							(mid -0.249642 -0.249642)
							(end -0.2794 -0.1778)
						)
						(arc
							(start -0.2794 0.1778)
							(mid -0.249642 0.249642)
							(end -0.1778 0.2794)
						)
						(arc
							(start 0.1778 0.2794)
							(mid 0.249642 0.249642)
							(end 0.2794 0.1778)
						)
						(arc
							(start 0.2794 -0.1778)
							(mid 0.249642 -0.249642)
							(end 0.1778 -0.2794)
						)
					)
					(width 0)
					(fill yes)
				)
			)
		)
		(pad "2" smd custom
			(at 0 0.4445 270)
			(size 0.1397 0.1397)
			(layers "F.Cu" "F.Mask" "F.Paste")
			(net "GND")
			(options
				(clearance outline)
				(anchor circle)
			)
			(primitives
				(gr_poly
					(pts
						(arc
							(start -0.1778 -0.2794)
							(mid -0.249642 -0.249642)
							(end -0.2794 -0.1778)
						)
						(arc
							(start -0.2794 0.1778)
							(mid -0.249642 0.249642)
							(end -0.1778 0.2794)
						)
						(arc
							(start 0.1778 0.2794)
							(mid 0.249642 0.249642)
							(end 0.2794 0.1778)
						)
						(arc
							(start 0.2794 -0.1778)
							(mid 0.249642 -0.249642)
							(end 0.1778 -0.2794)
						)
					)
					(width 0)
					(fill yes)
				)
			)
		)
	)
	(footprint ""
		(layer "F.Cu")
		(at 264.788142 -212.268562 90)
		(property "Reference" "R404"
			(at 0 0 90)
			(layer "F.SilkS")
			(hide yes)
			(effects
				(font
					(size 1.27 1.27)
				)
			)
		)
		(property "Value" "0R2J-2-GP"
			(at 0.064008 -3.993896 90)
			(unlocked yes)
			(layer "F.Fab")
			(hide yes)
			(effects
				(font
					(size 1.016 1.016)
					(thickness 0.1524)
				)
			)
		)
		(property "Device Type" "R402H16"
			(at 0.064008 -5.517896 90)
			(unlocked yes)
			(layer "F.Fab")
			(hide yes)
			(effects
				(font
					(size 1.016 1.016)
					(thickness 0.1524)
				)
			)
		)
		(duplicate_pad_numbers_are_jumpers no)
		(fp_line
			(start 0.508 -0.9398)
			(end -0.508 -0.9398)
			(stroke
				(width 0.1524)
				(type default)
			)
			(layer "F.SilkS")
		)
		(fp_line
			(start -0.508 -0.9398)
			(end -0.508 0.9398)
			(stroke
				(width 0.1524)
				(type default)
			)
			(layer "F.SilkS")
		)
		(fp_rect
			(start -0.508 0.9398)
			(end 0.508 -0.9398)
			(stroke
				(width 0)
				(type default)
			)
			(fill no)
			(layer "F.CrtYd")
		)
		(fp_rect
			(start -0.508 0.9398)
			(end 0.508 -0.9398)
			(stroke
				(width 0)
				(type default)
			)
			(fill no)
			(layer "F.Fab")
		)
		(pad "1" smd custom
			(at 0 -0.4445 90)
			(size 0.1397 0.1397)
			(layers "F.Cu" "F.Mask" "F.Paste")
			(net "I2C_DPB_A_SCL_BUF")
			(options
				(clearance outline)
				(anchor circle)
			)
			(primitives
				(gr_poly
					(pts
						(arc
							(start -0.1778 -0.2794)
							(mid -0.249642 -0.249642)
							(end -0.2794 -0.1778)
						)
						(arc
							(start -0.2794 0.1778)
							(mid -0.249642 0.249642)
							(end -0.1778 0.2794)
						)
						(arc
							(start 0.1778 0.2794)
							(mid 0.249642 0.249642)
							(end 0.2794 0.1778)
						)
						(arc
							(start 0.2794 -0.1778)
							(mid 0.249642 -0.249642)
							(end 0.1778 -0.2794)
						)
					)
					(width 0)
					(fill yes)
				)
			)
		)
		(pad "2" smd custom
			(at 0 0.4445 90)
			(size 0.1397 0.1397)
			(layers "F.Cu" "F.Mask" "F.Paste")
			(net "I2C_DPB_A_SCL")
			(options
				(clearance outline)
				(anchor circle)
			)
			(primitives
				(gr_poly
					(pts
						(arc
							(start -0.1778 -0.2794)
							(mid -0.249642 -0.249642)
							(end -0.2794 -0.1778)
						)
						(arc
							(start -0.2794 0.1778)
							(mid -0.249642 0.249642)
							(end -0.1778 0.2794)
						)
						(arc
							(start 0.1778 0.2794)
							(mid 0.249642 0.249642)
							(end 0.2794 0.1778)
						)
						(arc
							(start 0.2794 -0.1778)
							(mid 0.249642 -0.249642)
							(end 0.1778 -0.2794)
						)
					)
					(width 0)
					(fill yes)
				)
			)
		)
	)
)
